# BASEBOARD_FAB2 (Tioga Pass) — schematic netlist excerpt (pin names and nets, part order shuffled) for the footprints in the layout excerpt that follows; sources: Cadence DE-HDL packaged netlist, KiCad conversion of Wiwynn_Tioga_Pass_MB.brd

R7P4  RES  42.2 1.0% EMPTY  pkg 0402  page 103 : A = CLK_100M_CPU1_PE_REFCLK_DN ; B = GND
R2T53  RES  665 1.0% CHIP  pkg 0402  page 138 : A = P3V3_STBY ; B = SMB_BMC_PMBUS_STBY_LVC3_SDA
C1R31  CAP_A  0.1UF 16V 10% X7R  pkg 0402V  page 139 : A = P1V5_LAN ; B = GND

(kicad_pcb
	(version 20260206)
	(generator "pcbnew")
	(generator_version "10.0")
	(general
		(thickness 1.6)
		(legacy_teardrops no)
	)
	(paper "A4")
	(title_block
		(title "Wiwynn_Tioga_Pass_MB.brd")
		(comment 1 "Tioga Pass / footprints 3326-3328 of 4770")
	)
	(layers
		(0 "F.Cu" signal "TOP")
		(4 "In1.Cu" signal "L2GND")
		(6 "In2.Cu" signal "L3")
		(8 "In3.Cu" signal "L4GND")
		(10 "In4.Cu" signal "L5")
		(12 "In5.Cu" signal "L6GND")
		(14 "In6.Cu" signal "L7VCC")
		(16 "In7.Cu" signal "L8VCC")
		(18 "In8.Cu" signal "L9GND")
		(20 "In9.Cu" signal "L10")
		(22 "In10.Cu" signal "L11GND")
		(24 "In11.Cu" signal "L12")
		(26 "In12.Cu" signal "L13GND")
		(2 "B.Cu" signal "BOTTOM")
		(9 "F.Adhes" user "F.Adhesive")
		(11 "B.Adhes" user "B.Adhesive")
		(13 "F.Paste" user "Package Geometry/Pastemask Top")
		(15 "B.Paste" user "Package Geometry/Pastemask Bottom")
		(5 "F.SilkS" user "Ref Des/Silkscreen Top")
		(7 "B.SilkS" user "Ref Des/Silkscreen Bottom")
		(1 "F.Mask" user "Board Geometry/Soldermask Top")
		(3 "B.Mask" user "Board Geometry/Soldermask Bottom")
		(17 "Dwgs.User" user "User.Drawings")
		(19 "Cmts.User" user "User.Comments")
		(21 "Eco1.User" user "User.Eco1")
		(23 "Eco2.User" user "User.Eco2")
		(25 "Edge.Cuts" user "Board Geometry/Outline")
		(27 "Margin" user)
		(31 "F.CrtYd" user "Package Geometry/Place Bound Top")
		(29 "B.CrtYd" user "Package Geometry/Place Bound Bottom")
		(35 "F.Fab" user "Ref Des/Assembly Top")
		(33 "B.Fab" user "Ref Des/Assembly Bottom")
	)
	(footprint ""
		(layer "B.Cu")
		(at 401.828 -73.406 180)
		(property "Reference" "R2T53"
			(at 0 0 0)
			(layer "B.SilkS")
			(hide yes)
			(effects
				(font
					(size 1.27 1.27)
				)
				(justify mirror)
			)
		)
		(property "Value" ""
			(at 0 0 0)
			(layer "B.Fab")
			(effects
				(font
					(size 1.27 1.27)
				)
				(justify mirror)
			)
		)
		(duplicate_pad_numbers_are_jumpers no)
		(fp_poly
			(pts
				(xy 0.2794 -0.1016) (xy -0.2794 -0.1016) (xy -0.2794 0.9906) (xy 0.2794 0.9906)
			)
			(stroke
				(width 0)
				(type default)
			)
			(fill no)
			(layer "B.CrtYd")
		)
		(fp_line
			(start 0.2794 0.9906)
			(end -0.2794 0.9906)
			(stroke
				(width 0.1)
				(type default)
			)
			(layer "B.Fab")
		)
		(fp_line
			(start 0.2794 -0.1016)
			(end 0.2794 0.9906)
			(stroke
				(width 0.1)
				(type default)
			)
			(layer "B.Fab")
		)
		(fp_line
			(start -0.2794 0.9906)
			(end -0.2794 -0.1016)
			(stroke
				(width 0.1)
				(type default)
			)
			(layer "B.Fab")
		)
		(fp_line
			(start -0.2794 -0.1016)
			(end 0.2794 -0.1016)
			(stroke
				(width 0.1)
				(type default)
			)
			(layer "B.Fab")
		)
		(pad "1" smd rect
			(at 0 0)
			(size 0.508 0.508)
			(layers "B.Cu" "B.Mask" "B.Paste")
			(net "P3V3_STBY")
		)
		(pad "2" smd rect
			(at 0 0.889)
			(size 0.508 0.508)
			(layers "B.Cu" "B.Mask" "B.Paste")
			(net "SMB_BMC_PMBUS_STBY_LVC3_SDA")
		)
		(zone
			(layer "B.Cu")
			(hatch none 0.5)
			(connect_pads
				(clearance 0)
			)
			(min_thickness 0.25)
			(keepout
				(tracks not_allowed)
				(vias allowed)
				(pads allowed)
				(copperpour not_allowed)
				(footprints allowed)
			)
			(placement
				(enabled no)
				(sheetname "")
			)
			(fill
				(thermal_gap 0.5)
				(thermal_bridge_width 0.5)
				(island_removal_mode 0)
			)
			(polygon
				(pts
					(xy 401.574 -74.041) (xy 402.082 -74.041) (xy 402.082 -73.66) (xy 401.574 -73.66)
				)
			)
		)
		(zone
			(layer "B.Cu")
			(hatch none 0.5)
			(connect_pads
				(clearance 0)
			)
			(min_thickness 0.25)
			(keepout
				(tracks allowed)
				(vias not_allowed)
				(pads allowed)
				(copperpour not_allowed)
				(footprints allowed)
			)
			(placement
				(enabled no)
				(sheetname "")
			)
			(fill
				(thermal_gap 0.5)
				(thermal_bridge_width 0.5)
				(island_removal_mode 0)
			)
			(polygon
				(pts
					(xy 401.574 -73.66) (xy 402.082 -73.66) (xy 402.082 -74.041) (xy 401.574 -74.041)
				)
			)
		)
	)
	(footprint ""
		(layer "B.Cu")
		(at 479.6917 -38.6334 90)
		(property "Reference" "C1R31"
			(at 0 0 90)
			(layer "B.SilkS")
			(hide yes)
			(effects
				(font
					(size 1.27 1.27)
				)
				(justify mirror)
			)
		)
		(property "Value" ""
			(at 0 0 90)
			(layer "B.Fab")
			(effects
				(font
					(size 1.27 1.27)
				)
				(justify mirror)
			)
		)
		(duplicate_pad_numbers_are_jumpers no)
		(fp_poly
			(pts
				(xy -0.3048 -0.1016) (xy -0.3048 0.9906) (xy 0.3048 0.9906) (xy 0.3048 -0.1016)
			)
			(stroke
				(width 0)
				(type default)
			)
			(fill no)
			(layer "B.CrtYd")
		)
		(fp_line
			(start 0.3048 -0.1016)
			(end 0.3048 0.9906)
			(stroke
				(width 0.1)
				(type default)
			)
			(layer "B.Fab")
		)
		(fp_line
			(start -0.3048 -0.1016)
			(end 0.3048 -0.1016)
			(stroke
				(width 0.1)
				(type default)
			)
			(layer "B.Fab")
		)
		(fp_line
			(start 0.3048 0.9906)
			(end -0.3048 0.9906)
			(stroke
				(width 0.1)
				(type default)
			)
			(layer "B.Fab")
		)
		(fp_line
			(start -0.3048 0.9906)
			(end -0.3048 -0.1016)
			(stroke
				(width 0.1)
				(type default)
			)
			(layer "B.Fab")
		)
		(pad "1" smd rect
			(at 0 0 270)
			(size 0.508 0.508)
			(layers "B.Cu" "B.Mask" "B.Paste")
			(net "P1V5_LAN")
		)
		(pad "2" smd rect
			(at 0 0.889 270)
			(size 0.508 0.508)
			(layers "B.Cu" "B.Mask" "B.Paste")
			(net "GND")
		)
		(zone
			(layer "B.Cu")
			(hatch none 0.5)
			(connect_pads
				(clearance 0)
			)
			(min_thickness 0.25)
			(keepout
				(tracks allowed)
				(vias not_allowed)
				(pads allowed)
				(copperpour not_allowed)
				(footprints allowed)
			)
			(placement
				(enabled no)
				(sheetname "")
			)
			(fill
				(thermal_gap 0.5)
				(thermal_bridge_width 0.5)
				(island_removal_mode 0)
			)
			(polygon
				(pts
					(xy 479.9457 -38.8874) (xy 479.9457 -38.3794) (xy 480.3267 -38.3794) (xy 480.3267 -38.8874)
				)
			)
		)
		(zone
			(layer "B.Cu")
			(hatch none 0.5)
			(connect_pads
				(clearance 0)
			)
			(min_thickness 0.25)
			(keepout
				(tracks not_allowed)
				(vias allowed)
				(pads allowed)
				(copperpour not_allowed)
				(footprints allowed)
			)
			(placement
				(enabled no)
				(sheetname "")
			)
			(fill
				(thermal_gap 0.5)
				(thermal_bridge_width 0.5)
				(island_removal_mode 0)
			)
			(polygon
				(pts
					(xy 480.3267 -38.8874) (xy 480.3267 -38.3794) (xy 479.9457 -38.3794) (xy 479.9457 -38.8874)
				)
			)
		)
	)
	(footprint ""
		(layer "B.Cu")
		(at 162.687 -81.788 90)
		(property "Reference" "R7P4"
			(at 0 0 90)
			(layer "B.SilkS")
			(hide yes)
			(effects
				(font
					(size 1.27 1.27)
				)
				(justify mirror)
			)
		)
		(property "Value" ""
			(at 0 0 90)
			(layer "B.Fab")
			(effects
				(font
					(size 1.27 1.27)
				)
				(justify mirror)
			)
		)
		(duplicate_pad_numbers_are_jumpers no)
		(fp_poly
			(pts
				(xy 0.2794 -0.1016) (xy -0.2794 -0.1016) (xy -0.2794 0.9906) (xy 0.2794 0.9906)
			)
			(stroke
				(width 0)
				(type default)
			)
			(fill no)
			(layer "B.CrtYd")
		)
		(fp_line
			(start 0.2794 -0.1016)
			(end 0.2794 0.9906)
			(stroke
				(width 0.1)
				(type default)
			)
			(layer "B.Fab")
		)
		(fp_line
			(start -0.2794 -0.1016)
			(end 0.2794 -0.1016)
			(stroke
				(width 0.1)
				(type default)
			)
			(layer "B.Fab")
		)
		(fp_line
			(start 0.2794 0.9906)
			(end -0.2794 0.9906)
			(stroke
				(width 0.1)
				(type default)
			)
			(layer "B.Fab")
		)
		(fp_line
			(start -0.2794 0.9906)
			(end -0.2794 -0.1016)
			(stroke
				(width 0.1)
				(type default)
			)
			(layer "B.Fab")
		)
		(pad "1" smd rect
			(at 0 0 270)
			(size 0.508 0.508)
			(layers "B.Cu" "B.Mask" "B.Paste")
			(net "CLK_100M_CPU1_PE_REFCLK_DN")
		)
		(pad "2" smd rect
			(at 0 0.889 270)
			(size 0.508 0.508)
			(layers "B.Cu" "B.Mask" "B.Paste")
			(net "GND")
		)
		(zone
			(layer "B.Cu")
			(hatch none 0.5)
			(connect_pads
				(clearance 0)
			)
			(min_thickness 0.25)
			(keepout
				(tracks allowed)
				(vias not_allowed)
				(pads allowed)
				(copperpour not_allowed)
				(footprints allowed)
			)
			(placement
				(enabled no)
				(sheetname "")
			)
			(fill
				(thermal_gap 0.5)
				(thermal_bridge_width 0.5)
				(island_removal_mode 0)
			)
			(polygon
				(pts
					(xy 162.941 -82.042) (xy 162.941 -81.534) (xy 163.322 -81.534) (xy 163.322 -82.042)
				)
			)
		)
		(zone
			(layer "B.Cu")
			(hatch none 0.5)
			(connect_pads
				(clearance 0)
			)
			(min_thickness 0.25)
			(keepout
				(tracks not_allowed)
				(vias allowed)
				(pads allowed)
				(copperpour not_allowed)
				(footprints allowed)
			)
			(placement
				(enabled no)
				(sheetname "")
			)
			(fill
				(thermal_gap 0.5)
				(thermal_bridge_width 0.5)
				(island_removal_mode 0)
			)
			(polygon
				(pts
					(xy 163.322 -82.042) (xy 163.322 -81.534) (xy 162.941 -81.534) (xy 162.941 -82.042)
				)
			)
		)
	)
)
